(kicad_pcb
	(version 20260206)
	(generator "pcbnew")
	(generator_version "10.0")
	(general
		(thickness 1.6)
		(legacy_teardrops no)
	)
	(paper "A4")
	(title_block
		(title "timecard-production-celestica-r4006 — R4006-B0001-02_R01.brd")
		(comment 1 "Time Appliance Project (Time Card) / footprints 211-216 of 1113")
	)
	(layers
		(0 "F.Cu" signal "TOP")
		(4 "In1.Cu" signal "L02_GND1")
		(6 "In2.Cu" signal "L03_SIG1")
		(8 "In3.Cu" signal "L04_GND2")
		(10 "In4.Cu" signal "L05_VCC1")
		(12 "In5.Cu" signal "L06_VCC2")
		(14 "In6.Cu" signal "L07_GND3")
		(16 "In7.Cu" signal "L08_SIG2")
		(18 "In8.Cu" signal "L09_GND4")
		(2 "B.Cu" signal "BOTTOM")
		(9 "F.Adhes" user "F.Adhesive")
		(11 "B.Adhes" user "B.Adhesive")
		(13 "F.Paste" user "Package Geometry/Pastemask Top")
		(15 "B.Paste" user "Package Geometry/Pastemask Bottom")
		(5 "F.SilkS" user "Ref Des/Silkscreen Top")
		(7 "B.SilkS" user "Ref Des/Silkscreen Bottom")
		(1 "F.Mask" user "Board Geometry/Soldermask Top")
		(3 "B.Mask" user "Board Geometry/Soldermask Bottom")
		(17 "Dwgs.User" user "User.Drawings")
		(19 "Cmts.User" user "User.Comments")
		(21 "Eco1.User" user "User.Eco1")
		(23 "Eco2.User" user "User.Eco2")
		(25 "Edge.Cuts" user "Board Geometry/Outline")
		(27 "Margin" user)
		(31 "F.CrtYd" user "Package Geometry/Place Bound Top")
		(29 "B.CrtYd" user "Package Geometry/Place Bound Bottom")
		(35 "F.Fab" user "Ref Des/Assembly Top")
		(33 "B.Fab" user "Ref Des/Assembly Bottom")
	)
	(footprint ""
		(layer "F.Cu")
		(at 46.609 -75.184 -90)
		(property "Reference" "R487"
			(at 0.381 -2.45237 90)
			(unlocked yes)
			(layer "F.SilkS")
			(effects
				(font
					(size 0.7874 0.5842)
					(thickness 0.1524)
				)
			)
		)
		(property "Value" "VAL*"
			(at 0.02032 2.13233 270)
			(unlocked yes)
			(layer "F.Fab")
			(hide yes)
			(effects
				(font
					(size 0.7874 0.5842)
					(thickness 0.1524)
				)
			)
		)
		(property "Tolerance" "TOL*"
			(at 0.044704 3.05435 270)
			(unlocked yes)
			(layer "Cmts.User")
			(hide yes)
			(effects
				(font
					(size 0.7874 0.5842)
					(thickness 0.1524)
				)
			)
		)
		(property "User Part Number" "PARTNUM*"
			(at 0.02032 4.024884 270)
			(unlocked yes)
			(layer "Cmts.User")
			(hide yes)
			(effects
				(font
					(size 0.7874 0.5842)
					(thickness 0.1524)
				)
			)
		)
		(property "Device Type" "RESISTOR-G155-14701-01,4.7KOHMA"
			(at 0.008382 1.210564 270)
			(unlocked yes)
			(layer "F.Fab")
			(hide yes)
			(effects
				(font
					(size 0.7874 0.5842)
					(thickness 0.1524)
				)
			)
		)
		(duplicate_pad_numbers_are_jumpers no)
		(fp_line
			(start -1.143 0.5588)
			(end 1.143 0.5588)
			(stroke
				(width 0.1)
				(type default)
			)
			(layer "F.SilkS")
		)
		(fp_line
			(start 1.143 0.5588)
			(end 1.143 -0.5588)
			(stroke
				(width 0.1)
				(type default)
			)
			(layer "F.SilkS")
		)
		(fp_line
			(start -1.143 -0.5588)
			(end -1.143 0.5588)
			(stroke
				(width 0.1)
				(type default)
			)
			(layer "F.SilkS")
		)
		(fp_line
			(start 1.143 -0.5588)
			(end -1.143 -0.5588)
			(stroke
				(width 0.1)
				(type default)
			)
			(layer "F.SilkS")
		)
		(fp_poly
			(pts
				(xy -1.143 0.5588) (xy 1.143 0.5588) (xy 1.143 -0.5588) (xy -1.143 -0.5588)
			)
			(stroke
				(width 0)
				(type default)
			)
			(fill no)
			(layer "F.CrtYd")
		)
		(fp_line
			(start -0.508 0.3048)
			(end 0.508 0.3048)
			(stroke
				(width 0.1)
				(type default)
			)
			(layer "F.Fab")
		)
		(fp_line
			(start 0.508 0.3048)
			(end 0.508 -0.3048)
			(stroke
				(width 0.1)
				(type default)
			)
			(layer "F.Fab")
		)
		(fp_line
			(start -0.508 -0.3048)
			(end -0.508 0.3048)
			(stroke
				(width 0.1)
				(type default)
			)
			(layer "F.Fab")
		)
		(fp_line
			(start 0.508 -0.3048)
			(end -0.508 -0.3048)
			(stroke
				(width 0.1)
				(type default)
			)
			(layer "F.Fab")
		)
		(pad "1" smd rect
			(at -0.5334 0 270)
			(size 0.7112 0.6096)
			(layers "F.Cu" "F.Mask" "F.Paste")
			(net "UNNAMED_525_CAPACITOR_I16_1")
		)
		(pad "2" smd rect
			(at 0.5334 0 270)
			(size 0.7112 0.6096)
			(layers "F.Cu" "F.Mask" "F.Paste")
			(net "UNNAMED_525_CAPACITOR_I14_1")
		)
		(zone
			(layer "F.Cu")
			(hatch none 0.5)
			(connect_pads
				(clearance 0)
			)
			(min_thickness 0.25)
			(keepout
				(tracks not_allowed)
				(vias allowed)
				(pads allowed)
				(copperpour not_allowed)
				(footprints allowed)
			)
			(placement
				(enabled no)
				(sheetname "")
			)
			(fill
				(thermal_gap 0.5)
				(thermal_bridge_width 0.5)
				(island_removal_mode 0)
			)
			(polygon
				(pts
					(xy 46.3042 -75.2602) (xy 46.3042 -75.1078) (xy 46.9138 -75.1078) (xy 46.9138 -75.2602)
				)
			)
		)
		(zone
			(layer "F.Cu")
			(hatch none 0.5)
			(connect_pads
				(clearance 0)
			)
			(min_thickness 0.25)
			(keepout
				(tracks allowed)
				(vias not_allowed)
				(pads allowed)
				(copperpour not_allowed)
				(footprints allowed)
			)
			(placement
				(enabled no)
				(sheetname "")
			)
			(fill
				(thermal_gap 0.5)
				(thermal_bridge_width 0.5)
				(island_removal_mode 0)
			)
			(polygon
				(pts
					(xy 46.3042 -75.2602) (xy 46.3042 -75.1078) (xy 46.9138 -75.1078) (xy 46.9138 -75.2602)
				)
			)
		)
	)
	(footprint ""
		(layer "F.Cu")
		(at 29.845 -75.184 -90)
		(property "Reference" "R481"
			(at -0.381 -2.19837 90)
			(unlocked yes)
			(layer "F.SilkS")
			(effects
				(font
					(size 0.7874 0.5842)
					(thickness 0.1524)
				)
			)
		)
		(property "Value" "VAL*"
			(at 0.02032 2.13233 270)
			(unlocked yes)
			(layer "F.Fab")
			(hide yes)
			(effects
				(font
					(size 0.7874 0.5842)
					(thickness 0.1524)
				)
			)
		)
		(property "Tolerance" "TOL*"
			(at 0.044704 3.05435 270)
			(unlocked yes)
			(layer "Cmts.User")
			(hide yes)
			(effects
				(font
					(size 0.7874 0.5842)
					(thickness 0.1524)
				)
			)
		)
		(property "User Part Number" "PARTNUM*"
			(at 0.02032 4.024884 270)
			(unlocked yes)
			(layer "Cmts.User")
			(hide yes)
			(effects
				(font
					(size 0.7874 0.5842)
					(thickness 0.1524)
				)
			)
		)
		(property "Device Type" "RESISTOR-G155-11003-01,100KOHMA"
			(at 0.008382 1.210564 270)
			(unlocked yes)
			(layer "F.Fab")
			(hide yes)
			(effects
				(font
					(size 0.7874 0.5842)
					(thickness 0.1524)
				)
			)
		)
		(duplicate_pad_numbers_are_jumpers no)
		(fp_line
			(start -1.143 0.5588)
			(end 1.143 0.5588)
			(stroke
				(width 0.1)
				(type default)
			)
			(layer "F.SilkS")
		)
		(fp_line
			(start 1.143 0.5588)
			(end 1.143 -0.5588)
			(stroke
				(width 0.1)
				(type default)
			)
			(layer "F.SilkS")
		)
		(fp_line
			(start -1.143 -0.5588)
			(end -1.143 0.5588)
			(stroke
				(width 0.1)
				(type default)
			)
			(layer "F.SilkS")
		)
		(fp_line
			(start 1.143 -0.5588)
			(end -1.143 -0.5588)
			(stroke
				(width 0.1)
				(type default)
			)
			(layer "F.SilkS")
		)
		(fp_poly
			(pts
				(xy -1.143 0.5588) (xy 1.143 0.5588) (xy 1.143 -0.5588) (xy -1.143 -0.5588)
			)
			(stroke
				(width 0)
				(type default)
			)
			(fill no)
			(layer "F.CrtYd")
		)
		(fp_line
			(start -0.508 0.3048)
			(end 0.508 0.3048)
			(stroke
				(width 0.1)
				(type default)
			)
			(layer "F.Fab")
		)
		(fp_line
			(start 0.508 0.3048)
			(end 0.508 -0.3048)
			(stroke
				(width 0.1)
				(type default)
			)
			(layer "F.Fab")
		)
		(fp_line
			(start -0.508 -0.3048)
			(end -0.508 0.3048)
			(stroke
				(width 0.1)
				(type default)
			)
			(layer "F.Fab")
		)
		(fp_line
			(start 0.508 -0.3048)
			(end -0.508 -0.3048)
			(stroke
				(width 0.1)
				(type default)
			)
			(layer "F.Fab")
		)
		(pad "1" smd rect
			(at -0.5334 0 270)
			(size 0.7112 0.6096)
			(layers "F.Cu" "F.Mask" "F.Paste")
			(net "R_FT4232_CHC_RX")
		)
		(pad "2" smd rect
			(at 0.5334 0 270)
			(size 0.7112 0.6096)
			(layers "F.Cu" "F.Mask" "F.Paste")
			(net "XP3R3V_FT4232")
		)
		(zone
			(layer "F.Cu")
			(hatch none 0.5)
			(connect_pads
				(clearance 0)
			)
			(min_thickness 0.25)
			(keepout
				(tracks allowed)
				(vias not_allowed)
				(pads allowed)
				(copperpour not_allowed)
				(footprints allowed)
			)
			(placement
				(enabled no)
				(sheetname "")
			)
			(fill
				(thermal_gap 0.5)
				(thermal_bridge_width 0.5)
				(island_removal_mode 0)
			)
			(polygon
				(pts
					(xy 29.5402 -75.2602) (xy 29.5402 -75.1078) (xy 30.1498 -75.1078) (xy 30.1498 -75.2602)
				)
			)
		)
		(zone
			(layer "F.Cu")
			(hatch none 0.5)
			(connect_pads
				(clearance 0)
			)
			(min_thickness 0.25)
			(keepout
				(tracks not_allowed)
				(vias allowed)
				(pads allowed)
				(copperpour not_allowed)
				(footprints allowed)
			)
			(placement
				(enabled no)
				(sheetname "")
			)
			(fill
				(thermal_gap 0.5)
				(thermal_bridge_width 0.5)
				(island_removal_mode 0)
			)
			(polygon
				(pts
					(xy 29.5402 -75.2602) (xy 29.5402 -75.1078) (xy 30.1498 -75.1078) (xy 30.1498 -75.2602)
				)
			)
		)
	)
	(footprint ""
		(layer "F.Cu")
		(at 36.466018 -26.934922)
		(property "Reference" "ME7"
			(at -0.398018 -4.420108 0)
			(unlocked yes)
			(layer "F.SilkS")
			(effects
				(font
					(size 0.7874 0.5842)
					(thickness 0.1524)
				)
			)
		)
		(property "Value" ""
			(at 0 0 0)
			(layer "F.Fab")
			(effects
				(font
					(size 1.27 1.27)
				)
			)
		)
		(duplicate_pad_numbers_are_jumpers no)
		(fp_poly
			(pts
				(arc
					(start 3.556 0)
					(mid -3.556 0)
					(end 3.556 0)
				)
			)
			(stroke
				(width 0)
				(type default)
			)
			(fill no)
			(layer "B.CrtYd")
		)
		(fp_poly
			(pts
				(arc
					(start 3.556 0)
					(mid -3.556 0)
					(end 3.556 0)
				)
			)
			(stroke
				(width 0)
				(type default)
			)
			(fill no)
			(layer "F.CrtYd")
		)
		(fp_circle
			(center 0 0)
			(end 3.048 0)
			(stroke
				(width 0.1)
				(type default)
			)
			(fill no)
			(layer "B.Fab")
		)
		(fp_circle
			(center 0 0)
			(end 3.048 0)
			(stroke
				(width 0.1)
				(type default)
			)
			(fill no)
			(layer "F.Fab")
		)
		(pad "" np_thru_hole circle
			(at 0 0)
			(size 2.286 2.286)
			(drill 2.54)
			(layers "*.Cu" "*.Mask")
			(padstack
				(mode front_inner_back)
				(layer "Inner"
					(shape circle)
					(size 2.286 2.286)
					(clearance 0.4445)
				)
				(layer "B.Cu"
					(shape circle)
					(size 2.286 2.286)
				)
			)
		)
		(zone
			(layers "F.Cu" "B.Cu" "In1.Cu" "In2.Cu" "In3.Cu" "In4.Cu" "In5.Cu" "In6.Cu"
				"In7.Cu" "In8.Cu"
			)
			(hatch none 0.5)
			(connect_pads
				(clearance 0)
			)
			(min_thickness 0.25)
			(keepout
				(tracks not_allowed)
				(vias allowed)
				(pads allowed)
				(copperpour not_allowed)
				(footprints allowed)
			)
			(placement
				(enabled no)
				(sheetname "")
			)
			(fill
				(thermal_gap 0.5)
				(thermal_bridge_width 0.5)
				(island_removal_mode 0)
			)
			(polygon
				(pts
					(arc
						(start 38.040818 -26.934922)
						(mid 34.891218 -26.934922)
						(end 38.040818 -26.934922)
					)
				)
			)
		)
	)
	(footprint ""
		(layer "F.Cu")
		(at 9.4234 -39.318692 90)
		(property "Reference" "R125"
			(at 2.337308 -0.17145 90)
			(unlocked yes)
			(layer "F.SilkS")
			(effects
				(font
					(size 0.635 0.4064)
					(thickness 0.1524)
				)
			)
		)
		(property "Value" "VAL*"
			(at 0.02032 2.13233 90)
			(unlocked yes)
			(layer "F.Fab")
			(hide yes)
			(effects
				(font
					(size 0.7874 0.5842)
					(thickness 0.1524)
				)
			)
		)
		(property "Device Type" "RESISTOR-G155-11000-01,100OHM,A"
			(at 0.008382 1.210564 90)
			(unlocked yes)
			(layer "F.Fab")
			(hide yes)
			(effects
				(font
					(size 0.7874 0.5842)
					(thickness 0.1524)
				)
			)
		)
		(property "User Part Number" "PARTNUM*"
			(at 0.02032 4.024884 90)
			(unlocked yes)
			(layer "Cmts.User")
			(hide yes)
			(effects
				(font
					(size 0.7874 0.5842)
					(thickness 0.1524)
				)
			)
		)
		(property "Tolerance" "TOL*"
			(at 0.044704 3.05435 90)
			(unlocked yes)
			(layer "Cmts.User")
			(hide yes)
			(effects
				(font
					(size 0.7874 0.5842)
					(thickness 0.1524)
				)
			)
		)
		(duplicate_pad_numbers_are_jumpers no)
		(fp_line
			(start 1.143 -0.5588)
			(end -1.143 -0.5588)
			(stroke
				(width 0.1)
				(type default)
			)
			(layer "F.SilkS")
		)
		(fp_line
			(start -1.143 -0.5588)
			(end -1.143 0.5588)
			(stroke
				(width 0.1)
				(type default)
			)
			(layer "F.SilkS")
		)
		(fp_line
			(start 1.143 0.5588)
			(end 1.143 -0.5588)
			(stroke
				(width 0.1)
				(type default)
			)
			(layer "F.SilkS")
		)
		(fp_line
			(start -1.143 0.5588)
			(end 1.143 0.5588)
			(stroke
				(width 0.1)
				(type default)
			)
			(layer "F.SilkS")
		)
		(fp_poly
			(pts
				(xy -1.143 0.5588) (xy 1.143 0.5588) (xy 1.143 -0.5588) (xy -1.143 -0.5588)
			)
			(stroke
				(width 0)
				(type default)
			)
			(fill no)
			(layer "F.CrtYd")
		)
		(fp_line
			(start 0.508 -0.3048)
			(end -0.508 -0.3048)
			(stroke
				(width 0.1)
				(type default)
			)
			(layer "F.Fab")
		)
		(fp_line
			(start -0.508 -0.3048)
			(end -0.508 0.3048)
			(stroke
				(width 0.1)
				(type default)
			)
			(layer "F.Fab")
		)
		(fp_line
			(start 0.508 0.3048)
			(end 0.508 -0.3048)
			(stroke
				(width 0.1)
				(type default)
			)
			(layer "F.Fab")
		)
		(fp_line
			(start -0.508 0.3048)
			(end 0.508 0.3048)
			(stroke
				(width 0.1)
				(type default)
			)
			(layer "F.Fab")
		)
		(pad "1" smd rect
			(at -0.5334 0 90)
			(size 0.7112 0.6096)
			(layers "F.Cu" "F.Mask" "F.Paste")
			(net "FPGA_OUT_SMA1_LED_GREEN_N")
		)
		(pad "2" smd rect
			(at 0.5334 0 90)
			(size 0.7112 0.6096)
			(layers "F.Cu" "F.Mask" "F.Paste")
			(net "UNNAMED_14_LED4PV14_I265_4")
		)
		(zone
			(layer "F.Cu")
			(hatch none 0.5)
			(connect_pads
				(clearance 0)
			)
			(min_thickness 0.25)
			(keepout
				(tracks not_allowed)
				(vias allowed)
				(pads allowed)
				(copperpour not_allowed)
				(footprints allowed)
			)
			(placement
				(enabled no)
				(sheetname "")
			)
			(fill
				(thermal_gap 0.5)
				(thermal_bridge_width 0.5)
				(island_removal_mode 0)
			)
			(polygon
				(pts
					(xy 9.7282 -39.242492) (xy 9.7282 -39.394892) (xy 9.1186 -39.394892) (xy 9.1186 -39.242492)
				)
			)
		)
		(zone
			(layer "F.Cu")
			(hatch none 0.5)
			(connect_pads
				(clearance 0)
			)
			(min_thickness 0.25)
			(keepout
				(tracks allowed)
				(vias not_allowed)
				(pads allowed)
				(copperpour not_allowed)
				(footprints allowed)
			)
			(placement
				(enabled no)
				(sheetname "")
			)
			(fill
				(thermal_gap 0.5)
				(thermal_bridge_width 0.5)
				(island_removal_mode 0)
			)
			(polygon
				(pts
					(xy 9.7282 -39.242492) (xy 9.7282 -39.394892) (xy 9.1186 -39.394892) (xy 9.1186 -39.242492)
				)
			)
		)
	)
	(footprint ""
		(layer "F.Cu")
		(at 151.257 -60.706)
		(property "Reference" "TP26"
			(at -0.7112 -1.48463 0)
			(unlocked yes)
			(layer "F.SilkS")
			(effects
				(font
					(size 0.7874 0.5842)
					(thickness 0.1524)
				)
				(justify left)
			)
		)
		(property "Value" ""
			(at 0 0 0)
			(layer "F.Fab")
			(effects
				(font
					(size 1.27 1.27)
				)
			)
		)
		(property "Device Type" "TP_PIONT-TP010CT020B030_PTH-TPA"
			(at -1.341882 0.996696 0)
			(unlocked yes)
			(layer "F.Fab")
			(hide yes)
			(effects
				(font
					(size 0.7874 0.5842)
					(thickness 0.000001)
				)
				(justify left)
			)
		)
		(duplicate_pad_numbers_are_jumpers no)
		(fp_poly
			(pts
				(arc
					(start 0.889 0)
					(mid -0.889 0)
					(end 0.889 0)
				)
			)
			(stroke
				(width 0)
				(type default)
			)
			(fill no)
			(layer "B.CrtYd")
		)
		(fp_poly
			(pts
				(arc
					(start 0.889 0)
					(mid -0.889 0)
					(end 0.889 0)
				)
			)
			(stroke
				(width 0)
				(type default)
			)
			(fill no)
			(layer "F.CrtYd")
		)
		(pad "1" thru_hole circle
			(at 0 0)
			(size 0.508 0.508)
			(drill 0.254)
			(layers "*.Cu" "*.Mask")
			(remove_unused_layers no)
			(net "R_SHT3X_RST_N")
			(clearance 0.1016)
			(padstack
				(mode front_inner_back)
				(layer "Inner"
					(shape circle)
					(size 0.508 0.508)
					(clearance 0.1016)
				)
				(layer "B.Cu"
					(shape circle)
					(size 0.762 0.762)
					(clearance -0.0254)
				)
			)
		)
	)
	(footprint ""
		(layer "F.Cu")
		(at 116.459 -29.464 -90)
		(property "Reference" "R438"
			(at 2.794 -0.80137 90)
			(unlocked yes)
			(layer "F.SilkS")
			(effects
				(font
					(size 0.7874 0.5842)
					(thickness 0.1524)
				)
			)
		)
		(property "Value" "VAL*"
			(at 0.02032 2.13233 270)
			(unlocked yes)
			(layer "F.Fab")
			(hide yes)
			(effects
				(font
					(size 0.7874 0.5842)
					(thickness 0.1524)
				)
			)
		)
		(property "Tolerance" "TOL*"
			(at 0.044704 3.05435 270)
			(unlocked yes)
			(layer "Cmts.User")
			(hide yes)
			(effects
				(font
					(size 0.7874 0.5842)
					(thickness 0.1524)
				)
			)
		)
		(property "User Part Number" "PARTNUM*"
			(at 0.02032 4.024884 270)
			(unlocked yes)
			(layer "Cmts.User")
			(hide yes)
			(effects
				(font
					(size 0.7874 0.5842)
					(thickness 0.1524)
				)
			)
		)
		(property "Device Type" "RESISTOR-G155-11002-01,10KOHM,A"
			(at 0.008382 1.210564 270)
			(unlocked yes)
			(layer "F.Fab")
			(hide yes)
			(effects
				(font
					(size 0.7874 0.5842)
					(thickness 0.1524)
				)
			)
		)
		(duplicate_pad_numbers_are_jumpers no)
		(fp_line
			(start -1.143 0.5588)
			(end 1.143 0.5588)
			(stroke
				(width 0.1)
				(type default)
			)
			(layer "F.SilkS")
		)
		(fp_line
			(start 1.143 0.5588)
			(end 1.143 -0.5588)
			(stroke
				(width 0.1)
				(type default)
			)
			(layer "F.SilkS")
		)
		(fp_line
			(start -1.143 -0.5588)
			(end -1.143 0.5588)
			(stroke
				(width 0.1)
				(type default)
			)
			(layer "F.SilkS")
		)
		(fp_line
			(start 1.143 -0.5588)
			(end -1.143 -0.5588)
			(stroke
				(width 0.1)
				(type default)
			)
			(layer "F.SilkS")
		)
		(fp_poly
			(pts
				(xy -1.143 0.5588) (xy 1.143 0.5588) (xy 1.143 -0.5588) (xy -1.143 -0.5588)
			)
			(stroke
				(width 0)
				(type default)
			)
			(fill no)
			(layer "F.CrtYd")
		)
		(fp_line
			(start -0.508 0.3048)
			(end 0.508 0.3048)
			(stroke
				(width 0.1)
				(type default)
			)
			(layer "F.Fab")
		)
		(fp_line
			(start 0.508 0.3048)
			(end 0.508 -0.3048)
			(stroke
				(width 0.1)
				(type default)
			)
			(layer "F.Fab")
		)
		(fp_line
			(start -0.508 -0.3048)
			(end -0.508 0.3048)
			(stroke
				(width 0.1)
				(type default)
			)
			(layer "F.Fab")
		)
		(fp_line
			(start 0.508 -0.3048)
			(end -0.508 -0.3048)
			(stroke
				(width 0.1)
				(type default)
			)
			(layer "F.Fab")
		)
		(pad "1" smd rect
			(at -0.5334 0 270)
			(size 0.7112 0.6096)
			(layers "F.Cu" "F.Mask" "F.Paste")
			(net "FPGA_IN_MAC_PPS_OUTN")
		)
		(pad "2" smd rect
			(at 0.5334 0 270)
			(size 0.7112 0.6096)
			(layers "F.Cu" "F.Mask" "F.Paste")
			(net "XP2R5V_FPGA")
		)
		(zone
			(layer "F.Cu")
			(hatch none 0.5)
			(connect_pads
				(clearance 0)
			)
			(min_thickness 0.25)
			(keepout
				(tracks allowed)
				(vias not_allowed)
				(pads allowed)
				(copperpour not_allowed)
				(footprints allowed)
			)
			(placement
				(enabled no)
				(sheetname "")
			)
			(fill
				(thermal_gap 0.5)
				(thermal_bridge_width 0.5)
				(island_removal_mode 0)
			)
			(polygon
				(pts
					(xy 116.1542 -29.5402) (xy 116.1542 -29.3878) (xy 116.7638 -29.3878) (xy 116.7638 -29.5402)
				)
			)
		)
		(zone
			(layer "F.Cu")
			(hatch none 0.5)
			(connect_pads
				(clearance 0)
			)
			(min_thickness 0.25)
			(keepout
				(tracks not_allowed)
				(vias allowed)
				(pads allowed)
				(copperpour not_allowed)
				(footprints allowed)
			)
			(placement
				(enabled no)
				(sheetname "")
			)
			(fill
				(thermal_gap 0.5)
				(thermal_bridge_width 0.5)
				(island_removal_mode 0)
			)
			(polygon
				(pts
					(xy 116.1542 -29.5402) (xy 116.1542 -29.3878) (xy 116.7638 -29.3878) (xy 116.7638 -29.5402)
				)
			)
		)
	)
)
